# T6G (Grand Teton) — schematic netlist excerpt (pin names and nets, part order shuffled) for the footprints in the layout excerpt that follows; sources: Cadence DE-HDL packaged netlist, KiCad conversion of 04192023_DAF0TMB3IC0_F0TG_MB_C_brd_V02_OCP.brd

R6084  Q_RES  4.7K 5% CHIP  pkg 0402LF  page 28 : A = PVDD11_S3_P0 ; B = SMB_CPU0_3_SDA
R369  Q_RES  1K 1% CHIP  pkg 0402LF  page 161 : A = PVDD18_S5_P1 ; B = SMB_CPU1_SEC_SDA
PC487_1  Q_CAP  22UF 16V 20% X6S  pkg C0805  page 194 : A = SW_P12V_AUX_PVDDCR_CPU0_P0_FLT ; B = GND

(kicad_pcb
	(version 20260206)
	(generator "pcbnew")
	(generator_version "10.0")
	(general
		(thickness 1.6)
		(legacy_teardrops no)
	)
	(paper "A4")
	(title_block
		(title "04192023_DAF0TMB3IC0_F0TG_MB_C_brd_V02_OCP.brd")
		(comment 1 "Grand Teton / footprints 5509-5511 of 8354")
	)
	(layers
		(0 "F.Cu" signal "TOP")
		(4 "In1.Cu" signal "GND")
		(6 "In2.Cu" signal "IN1")
		(8 "In3.Cu" signal "GND1")
		(10 "In4.Cu" signal "IN2")
		(12 "In5.Cu" signal "GND2")
		(14 "In6.Cu" signal "IN3")
		(16 "In7.Cu" signal "GND3")
		(18 "In8.Cu" signal "VCC")
		(20 "In9.Cu" signal "VCC1")
		(22 "In10.Cu" signal "GND4")
		(24 "In11.Cu" signal "IN4")
		(26 "In12.Cu" signal "GND5")
		(28 "In13.Cu" signal "IN5")
		(30 "In14.Cu" signal "GND6")
		(32 "In15.Cu" signal "IN6")
		(34 "In16.Cu" signal "GND7")
		(2 "B.Cu" signal "BOTTOM")
		(9 "F.Adhes" user "F.Adhesive")
		(11 "B.Adhes" user "B.Adhesive")
		(13 "F.Paste" user "Package Geometry/Pastemask Top")
		(15 "B.Paste" user "Package Geometry/Pastemask Bottom")
		(5 "F.SilkS" user "Ref Des/Silkscreen Top")
		(7 "B.SilkS" user "Ref Des/Silkscreen Bottom")
		(1 "F.Mask" user "Board Geometry/Soldermask Top")
		(3 "B.Mask" user "Board Geometry/Soldermask Bottom")
		(17 "Dwgs.User" user "User.Drawings")
		(19 "Cmts.User" user "User.Comments")
		(21 "Eco1.User" user "User.Eco1")
		(23 "Eco2.User" user "User.Eco2")
		(25 "Edge.Cuts" user "Board Geometry/Outline")
		(27 "Margin" user)
		(31 "F.CrtYd" user "Package Geometry/Place Bound Top")
		(29 "B.CrtYd" user "Package Geometry/Place Bound Bottom")
		(35 "F.Fab" user "Ref Des/Assembly Top")
		(33 "B.Fab" user "Ref Des/Assembly Bottom")
	)
	(footprint ""
		(layer "B.Cu")
		(at 235.077 -231.648 -90)
		(property "Reference" "R369"
			(at 0 0 90)
			(layer "B.SilkS")
			(hide yes)
			(effects
				(font
					(size 1.27 1.27)
				)
				(justify mirror)
			)
		)
		(property "Value" ""
			(at 0 0 90)
			(layer "B.Fab")
			(effects
				(font
					(size 1.27 1.27)
				)
				(justify mirror)
			)
		)
		(duplicate_pad_numbers_are_jumpers no)
		(fp_line
			(start -0.7874 0.4064)
			(end 0.7874 0.4064)
			(stroke
				(width 0.1524)
				(type default)
			)
			(layer "B.SilkS")
		)
		(fp_line
			(start 0.7874 0.4064)
			(end 0.7874 -0.4064)
			(stroke
				(width 0.1524)
				(type default)
			)
			(layer "B.SilkS")
		)
		(fp_line
			(start -0.7874 -0.4064)
			(end -0.7874 0.4064)
			(stroke
				(width 0.1524)
				(type default)
			)
			(layer "B.SilkS")
		)
		(fp_line
			(start 0.7874 -0.4064)
			(end -0.7874 -0.4064)
			(stroke
				(width 0.1524)
				(type default)
			)
			(layer "B.SilkS")
		)
		(fp_line
			(start -0.67945 0.3048)
			(end -0.120396 0.3048)
			(stroke
				(width 0.1)
				(type default)
			)
			(layer "B.Fab")
		)
		(fp_line
			(start -0.120396 0.3048)
			(end -0.120396 0.2794)
			(stroke
				(width 0.1)
				(type default)
			)
			(layer "B.Fab")
		)
		(fp_line
			(start 0.12065 0.3048)
			(end 0.67945 0.3048)
			(stroke
				(width 0.1)
				(type default)
			)
			(layer "B.Fab")
		)
		(fp_line
			(start 0.67945 0.3048)
			(end 0.67945 -0.305054)
			(stroke
				(width 0.1)
				(type default)
			)
			(layer "B.Fab")
		)
		(fp_line
			(start -0.120396 0.2794)
			(end 0.12065 0.2794)
			(stroke
				(width 0.1)
				(type default)
			)
			(layer "B.Fab")
		)
		(fp_line
			(start 0.12065 0.2794)
			(end 0.12065 0.3048)
			(stroke
				(width 0.1)
				(type default)
			)
			(layer "B.Fab")
		)
		(fp_line
			(start -0.12065 -0.2794)
			(end -0.12065 -0.3048)
			(stroke
				(width 0.1)
				(type default)
			)
			(layer "B.Fab")
		)
		(fp_line
			(start 0.12065 -0.2794)
			(end -0.12065 -0.2794)
			(stroke
				(width 0.1)
				(type default)
			)
			(layer "B.Fab")
		)
		(fp_line
			(start -0.67945 -0.3048)
			(end -0.67945 0.3048)
			(stroke
				(width 0.1)
				(type default)
			)
			(layer "B.Fab")
		)
		(fp_line
			(start -0.12065 -0.3048)
			(end -0.67945 -0.3048)
			(stroke
				(width 0.1)
				(type default)
			)
			(layer "B.Fab")
		)
		(fp_line
			(start 0.12065 -0.305054)
			(end 0.12065 -0.2794)
			(stroke
				(width 0.1)
				(type default)
			)
			(layer "B.Fab")
		)
		(fp_line
			(start 0.67945 -0.305054)
			(end 0.12065 -0.305054)
			(stroke
				(width 0.1)
				(type default)
			)
			(layer "B.Fab")
		)
		(pad "1" smd circle
			(at 0.40005 0 90)
			(size 0 0)
			(layers "B.Cu" "B.Mask" "B.Paste")
			(net "PVDD18_S5_P1")
		)
		(pad "2" smd circle
			(at -0.40005 0 90)
			(size 0 0)
			(layers "B.Cu" "B.Mask" "B.Paste")
			(net "SMB_CPU1_SEC_SDA")
		)
	)
	(footprint ""
		(layer "B.Cu")
		(at 391.636758 -203.50099)
		(property "Reference" "R6084"
			(at 0 0 0)
			(layer "B.SilkS")
			(hide yes)
			(effects
				(font
					(size 1.27 1.27)
				)
				(justify mirror)
			)
		)
		(property "Value" ""
			(at 0 0 0)
			(layer "B.Fab")
			(effects
				(font
					(size 1.27 1.27)
				)
				(justify mirror)
			)
		)
		(duplicate_pad_numbers_are_jumpers no)
		(fp_line
			(start -0.7874 -0.4064)
			(end -0.7874 0.4064)
			(stroke
				(width 0.1524)
				(type default)
			)
			(layer "B.SilkS")
		)
		(fp_line
			(start -0.7874 0.4064)
			(end 0.7874 0.4064)
			(stroke
				(width 0.1524)
				(type default)
			)
			(layer "B.SilkS")
		)
		(fp_line
			(start 0.7874 -0.4064)
			(end -0.7874 -0.4064)
			(stroke
				(width 0.1524)
				(type default)
			)
			(layer "B.SilkS")
		)
		(fp_line
			(start 0.7874 0.4064)
			(end 0.7874 -0.4064)
			(stroke
				(width 0.1524)
				(type default)
			)
			(layer "B.SilkS")
		)
		(fp_line
			(start -0.67945 -0.3048)
			(end -0.67945 0.3048)
			(stroke
				(width 0.1)
				(type default)
			)
			(layer "B.Fab")
		)
		(fp_line
			(start -0.67945 0.3048)
			(end -0.120396 0.3048)
			(stroke
				(width 0.1)
				(type default)
			)
			(layer "B.Fab")
		)
		(fp_line
			(start -0.12065 -0.3048)
			(end -0.67945 -0.3048)
			(stroke
				(width 0.1)
				(type default)
			)
			(layer "B.Fab")
		)
		(fp_line
			(start -0.12065 -0.2794)
			(end -0.12065 -0.3048)
			(stroke
				(width 0.1)
				(type default)
			)
			(layer "B.Fab")
		)
		(fp_line
			(start -0.120396 0.2794)
			(end 0.12065 0.2794)
			(stroke
				(width 0.1)
				(type default)
			)
			(layer "B.Fab")
		)
		(fp_line
			(start -0.120396 0.3048)
			(end -0.120396 0.2794)
			(stroke
				(width 0.1)
				(type default)
			)
			(layer "B.Fab")
		)
		(fp_line
			(start 0.12065 -0.305054)
			(end 0.12065 -0.2794)
			(stroke
				(width 0.1)
				(type default)
			)
			(layer "B.Fab")
		)
		(fp_line
			(start 0.12065 -0.2794)
			(end -0.12065 -0.2794)
			(stroke
				(width 0.1)
				(type default)
			)
			(layer "B.Fab")
		)
		(fp_line
			(start 0.12065 0.2794)
			(end 0.12065 0.3048)
			(stroke
				(width 0.1)
				(type default)
			)
			(layer "B.Fab")
		)
		(fp_line
			(start 0.12065 0.3048)
			(end 0.67945 0.3048)
			(stroke
				(width 0.1)
				(type default)
			)
			(layer "B.Fab")
		)
		(fp_line
			(start 0.67945 -0.305054)
			(end 0.12065 -0.305054)
			(stroke
				(width 0.1)
				(type default)
			)
			(layer "B.Fab")
		)
		(fp_line
			(start 0.67945 0.3048)
			(end 0.67945 -0.305054)
			(stroke
				(width 0.1)
				(type default)
			)
			(layer "B.Fab")
		)
		(pad "1" smd circle
			(at 0.40005 0 180)
			(size 0 0)
			(layers "B.Cu" "B.Mask" "B.Paste")
			(net "PVDD11_S3_P0")
		)
		(pad "2" smd circle
			(at -0.40005 0 180)
			(size 0 0)
			(layers "B.Cu" "B.Mask" "B.Paste")
			(net "SMB_CPU0_3_SDA")
		)
	)
	(footprint ""
		(layer "B.Cu")
		(at 361.255056 -177.894996 -90)
		(property "Reference" "PC487_1"
			(at 0 0 90)
			(layer "B.SilkS")
			(hide yes)
			(effects
				(font
					(size 1.27 1.27)
				)
				(justify mirror)
			)
		)
		(property "Value" ""
			(at 0 0 90)
			(layer "B.Fab")
			(effects
				(font
					(size 1.27 1.27)
				)
				(justify mirror)
			)
		)
		(duplicate_pad_numbers_are_jumpers no)
		(fp_line
			(start -1.524 0.762)
			(end 1.524 0.762)
			(stroke
				(width 0.1524)
				(type default)
			)
			(layer "B.SilkS")
		)
		(fp_line
			(start 1.524 0.762)
			(end 1.524 -0.762)
			(stroke
				(width 0.1524)
				(type default)
			)
			(layer "B.SilkS")
		)
		(fp_line
			(start -1.524 -0.762)
			(end -1.524 0.762)
			(stroke
				(width 0.1524)
				(type default)
			)
			(layer "B.SilkS")
		)
		(fp_line
			(start 1.524 -0.762)
			(end -1.524 -0.762)
			(stroke
				(width 0.1524)
				(type default)
			)
			(layer "B.SilkS")
		)
		(fp_line
			(start -1.1049 0.724916)
			(end -1.1049 -0.724916)
			(stroke
				(width 0.1)
				(type default)
			)
			(layer "B.Fab")
		)
		(fp_line
			(start 1.1049 0.724916)
			(end -1.1049 0.724916)
			(stroke
				(width 0.1)
				(type default)
			)
			(layer "B.Fab")
		)
		(fp_line
			(start -1.1049 -0.724916)
			(end 1.1049 -0.724916)
			(stroke
				(width 0.1)
				(type default)
			)
			(layer "B.Fab")
		)
		(fp_line
			(start 1.1049 -0.724916)
			(end 1.1049 0.724916)
			(stroke
				(width 0.1)
				(type default)
			)
			(layer "B.Fab")
		)
		(pad "1" smd rect
			(at 0.889 0 270)
			(size 1.016 1.27)
			(layers "B.Cu" "B.Mask" "B.Paste")
			(net "SW_P12V_AUX_PVDDCR_CPU0_P0_FLT")
		)
		(pad "2" smd rect
			(at -0.889 0 270)
			(size 1.016 1.27)
			(layers "B.Cu" "B.Mask" "B.Paste")
			(net "GND")
		)
	)
)
